(kicad_pcb
	(version 20260206)
	(generator "pcbnew")
	(generator_version "10.0")
	(general
		(thickness 1.6)
		(legacy_teardrops no)
	)
	(paper "A4")
	(title_block
		(title "01162023_DA0F0TEBIF0_F0T_Expander_BD_F_brd_V02_OCP.brd")
		(comment 1 "Grand Teton / footprints 2813-2819 of 9728")
	)
	(layers
		(0 "F.Cu" signal "TOP")
		(4 "In1.Cu" signal "GND")
		(6 "In2.Cu" signal "VCC")
		(8 "In3.Cu" signal "VCC1")
		(10 "In4.Cu" signal "GND1")
		(12 "In5.Cu" signal "IN1")
		(14 "In6.Cu" signal "GND2")
		(16 "In7.Cu" signal "IN2")
		(18 "In8.Cu" signal "GND3")
		(20 "In9.Cu" signal "IN3")
		(22 "In10.Cu" signal "GND4")
		(24 "In11.Cu" signal "IN4")
		(26 "In12.Cu" signal "GND5")
		(28 "In13.Cu" signal "IN5")
		(30 "In14.Cu" signal "GND6")
		(32 "In15.Cu" signal "IN6")
		(34 "In16.Cu" signal "GND7")
		(2 "B.Cu" signal "BOTTOM")
		(9 "F.Adhes" user "F.Adhesive")
		(11 "B.Adhes" user "B.Adhesive")
		(13 "F.Paste" user "Package Geometry/Pastemask Top")
		(15 "B.Paste" user "Package Geometry/Pastemask Bottom")
		(5 "F.SilkS" user "Ref Des/Silkscreen Top")
		(7 "B.SilkS" user "Ref Des/Silkscreen Bottom")
		(1 "F.Mask" user "Board Geometry/Soldermask Top")
		(3 "B.Mask" user "Board Geometry/Soldermask Bottom")
		(17 "Dwgs.User" user "User.Drawings")
		(19 "Cmts.User" user "User.Comments")
		(21 "Eco1.User" user "User.Eco1")
		(23 "Eco2.User" user "User.Eco2")
		(25 "Edge.Cuts" user "Board Geometry/Outline")
		(27 "Margin" user)
		(31 "F.CrtYd" user "Package Geometry/Place Bound Top")
		(29 "B.CrtYd" user "Package Geometry/Place Bound Bottom")
		(35 "F.Fab" user "Ref Des/Assembly Top")
		(33 "B.Fab" user "Ref Des/Assembly Bottom")
	)
	(footprint ""
		(layer "F.Cu")
		(at 142.50543 -258.582922 90)
		(property "Reference" "L113"
			(at 0 0 90)
			(layer "F.SilkS")
			(hide yes)
			(effects
				(font
					(size 1.27 1.27)
				)
			)
		)
		(property "Value" ""
			(at 0 0 90)
			(layer "F.Fab")
			(effects
				(font
					(size 1.27 1.27)
				)
			)
		)
		(duplicate_pad_numbers_are_jumpers no)
		(fp_line
			(start 1.63576 -0.8128)
			(end 1.63576 0.8128)
			(stroke
				(width 0.1524)
				(type default)
			)
			(layer "F.SilkS")
		)
		(fp_line
			(start -1.63576 -0.8128)
			(end 1.63576 -0.8128)
			(stroke
				(width 0.1524)
				(type default)
			)
			(layer "F.SilkS")
		)
		(fp_line
			(start -1.63576 -0.8128)
			(end -1.63576 0.8128)
			(stroke
				(width 0.1524)
				(type default)
			)
			(layer "F.SilkS")
		)
		(fp_line
			(start 1.63576 0.8128)
			(end -1.63576 0.8128)
			(stroke
				(width 0.1524)
				(type default)
			)
			(layer "F.SilkS")
		)
		(fp_line
			(start 1.560576 -0.738632)
			(end -1.56083 -0.738632)
			(stroke
				(width 0.1)
				(type default)
			)
			(layer "F.Fab")
		)
		(fp_line
			(start -1.56083 -0.738632)
			(end -1.56083 0.7366)
			(stroke
				(width 0.1)
				(type default)
			)
			(layer "F.Fab")
		)
		(fp_line
			(start 1.560576 0.7366)
			(end 1.560576 -0.738632)
			(stroke
				(width 0.1)
				(type default)
			)
			(layer "F.Fab")
		)
		(fp_line
			(start 1.524 0.7366)
			(end 1.560576 0.7366)
			(stroke
				(width 0.1)
				(type default)
			)
			(layer "F.Fab")
		)
		(fp_line
			(start -1.524 0.7366)
			(end 1.524 0.7366)
			(stroke
				(width 0.1)
				(type default)
			)
			(layer "F.Fab")
		)
		(fp_line
			(start -1.56083 0.7366)
			(end -1.524 0.7366)
			(stroke
				(width 0.1)
				(type default)
			)
			(layer "F.Fab")
		)
		(pad "1" smd rect
			(at -0.94996 0 270)
			(size 1.1176 1.3716)
			(layers "F.Cu" "F.Mask" "F.Paste")
			(net "P1V8_PLL0_PEX1")
		)
		(pad "2" smd rect
			(at 0.94996 0 270)
			(size 1.1176 1.3716)
			(layers "F.Cu" "F.Mask" "F.Paste")
			(net "P1V8_VDDA_PEX1")
		)
	)
	(footprint ""
		(layer "F.Cu")
		(at 436.049674 -300.60265 90)
		(property "Reference" "R6400"
			(at 0 0 90)
			(layer "F.SilkS")
			(hide yes)
			(effects
				(font
					(size 1.27 1.27)
				)
			)
		)
		(property "Value" ""
			(at 0 0 90)
			(layer "F.Fab")
			(effects
				(font
					(size 1.27 1.27)
				)
			)
		)
		(duplicate_pad_numbers_are_jumpers no)
		(fp_line
			(start 0.7874 -0.4064)
			(end 0.7874 0.4064)
			(stroke
				(width 0.1524)
				(type default)
			)
			(layer "F.SilkS")
		)
		(fp_line
			(start -0.7874 -0.4064)
			(end 0.7874 -0.4064)
			(stroke
				(width 0.1524)
				(type default)
			)
			(layer "F.SilkS")
		)
		(fp_line
			(start 0.7874 0.4064)
			(end -0.7874 0.4064)
			(stroke
				(width 0.1524)
				(type default)
			)
			(layer "F.SilkS")
		)
		(fp_line
			(start -0.7874 0.4064)
			(end -0.7874 -0.4064)
			(stroke
				(width 0.1524)
				(type default)
			)
			(layer "F.SilkS")
		)
		(fp_line
			(start -0.12065 -0.305054)
			(end -0.12065 -0.2794)
			(stroke
				(width 0.1)
				(type default)
			)
			(layer "F.Fab")
		)
		(fp_line
			(start -0.67945 -0.305054)
			(end -0.12065 -0.305054)
			(stroke
				(width 0.1)
				(type default)
			)
			(layer "F.Fab")
		)
		(fp_line
			(start 0.67945 -0.3048)
			(end 0.67945 0.3048)
			(stroke
				(width 0.1)
				(type default)
			)
			(layer "F.Fab")
		)
		(fp_line
			(start 0.12065 -0.3048)
			(end 0.67945 -0.3048)
			(stroke
				(width 0.1)
				(type default)
			)
			(layer "F.Fab")
		)
		(fp_line
			(start 0.12065 -0.2794)
			(end 0.12065 -0.3048)
			(stroke
				(width 0.1)
				(type default)
			)
			(layer "F.Fab")
		)
		(fp_line
			(start -0.12065 -0.2794)
			(end 0.12065 -0.2794)
			(stroke
				(width 0.1)
				(type default)
			)
			(layer "F.Fab")
		)
		(fp_line
			(start 0.120396 0.2794)
			(end -0.12065 0.2794)
			(stroke
				(width 0.1)
				(type default)
			)
			(layer "F.Fab")
		)
		(fp_line
			(start -0.12065 0.2794)
			(end -0.12065 0.3048)
			(stroke
				(width 0.1)
				(type default)
			)
			(layer "F.Fab")
		)
		(fp_line
			(start 0.67945 0.3048)
			(end 0.120396 0.3048)
			(stroke
				(width 0.1)
				(type default)
			)
			(layer "F.Fab")
		)
		(fp_line
			(start 0.120396 0.3048)
			(end 0.120396 0.2794)
			(stroke
				(width 0.1)
				(type default)
			)
			(layer "F.Fab")
		)
		(fp_line
			(start -0.12065 0.3048)
			(end -0.67945 0.3048)
			(stroke
				(width 0.1)
				(type default)
			)
			(layer "F.Fab")
		)
		(fp_line
			(start -0.67945 0.3048)
			(end -0.67945 -0.305054)
			(stroke
				(width 0.1)
				(type default)
			)
			(layer "F.Fab")
		)
		(pad "1" smd circle
			(at -0.40005 0 90)
			(size 0 0)
			(layers "F.Cu" "F.Mask" "F.Paste")
			(net "RST_PEX3_S1_PERST_N")
		)
		(pad "2" smd circle
			(at 0.40005 0 90)
			(size 0 0)
			(layers "F.Cu" "F.Mask" "F.Paste")
			(net "RST_PEX3_S1_PERST_R_N")
		)
	)
	(footprint ""
		(layer "F.Cu")
		(at 338.074 -171.069 180)
		(property "Reference" "R4768"
			(at 0 0 180)
			(layer "F.SilkS")
			(hide yes)
			(effects
				(font
					(size 1.27 1.27)
				)
			)
		)
		(property "Value" ""
			(at 0 0 180)
			(layer "F.Fab")
			(effects
				(font
					(size 1.27 1.27)
				)
			)
		)
		(duplicate_pad_numbers_are_jumpers no)
		(fp_line
			(start 0.7874 0.4064)
			(end -0.7874 0.4064)
			(stroke
				(width 0.1524)
				(type default)
			)
			(layer "F.SilkS")
		)
		(fp_line
			(start 0.7874 -0.4064)
			(end 0.7874 0.4064)
			(stroke
				(width 0.1524)
				(type default)
			)
			(layer "F.SilkS")
		)
		(fp_line
			(start -0.7874 0.4064)
			(end -0.7874 -0.4064)
			(stroke
				(width 0.1524)
				(type default)
			)
			(layer "F.SilkS")
		)
		(fp_line
			(start -0.7874 -0.4064)
			(end 0.7874 -0.4064)
			(stroke
				(width 0.1524)
				(type default)
			)
			(layer "F.SilkS")
		)
		(fp_line
			(start 0.67945 0.3048)
			(end 0.120396 0.3048)
			(stroke
				(width 0.1)
				(type default)
			)
			(layer "F.Fab")
		)
		(fp_line
			(start 0.67945 -0.3048)
			(end 0.67945 0.3048)
			(stroke
				(width 0.1)
				(type default)
			)
			(layer "F.Fab")
		)
		(fp_line
			(start 0.12065 -0.2794)
			(end 0.12065 -0.3048)
			(stroke
				(width 0.1)
				(type default)
			)
			(layer "F.Fab")
		)
		(fp_line
			(start 0.12065 -0.3048)
			(end 0.67945 -0.3048)
			(stroke
				(width 0.1)
				(type default)
			)
			(layer "F.Fab")
		)
		(fp_line
			(start 0.120396 0.3048)
			(end 0.120396 0.2794)
			(stroke
				(width 0.1)
				(type default)
			)
			(layer "F.Fab")
		)
		(fp_line
			(start 0.120396 0.2794)
			(end -0.12065 0.2794)
			(stroke
				(width 0.1)
				(type default)
			)
			(layer "F.Fab")
		)
		(fp_line
			(start -0.12065 0.3048)
			(end -0.67945 0.3048)
			(stroke
				(width 0.1)
				(type default)
			)
			(layer "F.Fab")
		)
		(fp_line
			(start -0.12065 0.2794)
			(end -0.12065 0.3048)
			(stroke
				(width 0.1)
				(type default)
			)
			(layer "F.Fab")
		)
		(fp_line
			(start -0.12065 -0.2794)
			(end 0.12065 -0.2794)
			(stroke
				(width 0.1)
				(type default)
			)
			(layer "F.Fab")
		)
		(fp_line
			(start -0.12065 -0.305054)
			(end -0.12065 -0.2794)
			(stroke
				(width 0.1)
				(type default)
			)
			(layer "F.Fab")
		)
		(fp_line
			(start -0.67945 0.3048)
			(end -0.67945 -0.305054)
			(stroke
				(width 0.1)
				(type default)
			)
			(layer "F.Fab")
		)
		(fp_line
			(start -0.67945 -0.305054)
			(end -0.12065 -0.305054)
			(stroke
				(width 0.1)
				(type default)
			)
			(layer "F.Fab")
		)
		(pad "1" smd circle
			(at -0.40005 0 180)
			(size 0 0)
			(layers "F.Cu" "F.Mask" "F.Paste")
			(net "PRSNT_SSD10_FPGA_PCA9555_N")
		)
		(pad "2" smd circle
			(at 0.40005 0 180)
			(size 0 0)
			(layers "F.Cu" "F.Mask" "F.Paste")
			(net "PRSNT_SSD10_FPGA_R_N")
		)
	)
	(footprint ""
		(layer "F.Cu")
		(at 207.015842 -309.760366 135)
		(property "Reference" "R1318"
			(at 0 0 135)
			(layer "F.SilkS")
			(hide yes)
			(effects
				(font
					(size 1.27 1.27)
				)
			)
		)
		(property "Value" ""
			(at 0 0 135)
			(layer "F.Fab")
			(effects
				(font
					(size 1.27 1.27)
				)
			)
		)
		(duplicate_pad_numbers_are_jumpers no)
		(fp_line
			(start 0.787389 -0.406267)
			(end 0.787389 0.406267)
			(stroke
				(width 0.1524)
				(type default)
			)
			(layer "F.SilkS")
		)
		(fp_line
			(start 0.787389 0.406267)
			(end -0.787389 0.406267)
			(stroke
				(width 0.1524)
				(type default)
			)
			(layer "F.SilkS")
		)
		(fp_line
			(start -0.787389 -0.406267)
			(end 0.787389 -0.406267)
			(stroke
				(width 0.1524)
				(type default)
			)
			(layer "F.SilkS")
		)
		(fp_line
			(start -0.787389 0.406267)
			(end -0.787389 -0.406267)
			(stroke
				(width 0.1524)
				(type default)
			)
			(layer "F.SilkS")
		)
		(fp_line
			(start 0.679446 -0.30479)
			(end 0.679446 0.30479)
			(stroke
				(width 0.1)
				(type default)
			)
			(layer "F.Fab")
		)
		(fp_line
			(start 0.120515 -0.30479)
			(end 0.679446 -0.30479)
			(stroke
				(width 0.1)
				(type default)
			)
			(layer "F.Fab")
		)
		(fp_line
			(start 0.120695 -0.279466)
			(end 0.120515 -0.30479)
			(stroke
				(width 0.1)
				(type default)
			)
			(layer "F.Fab")
		)
		(fp_line
			(start 0.679446 0.30479)
			(end 0.120515 0.30479)
			(stroke
				(width 0.1)
				(type default)
			)
			(layer "F.Fab")
		)
		(fp_line
			(start -0.120695 -0.304969)
			(end -0.120695 -0.279466)
			(stroke
				(width 0.1)
				(type default)
			)
			(layer "F.Fab")
		)
		(fp_line
			(start -0.120695 -0.279466)
			(end 0.120695 -0.279466)
			(stroke
				(width 0.1)
				(type default)
			)
			(layer "F.Fab")
		)
		(fp_line
			(start 0.120335 0.279466)
			(end -0.120695 0.279466)
			(stroke
				(width 0.1)
				(type default)
			)
			(layer "F.Fab")
		)
		(fp_line
			(start 0.120515 0.30479)
			(end 0.120335 0.279466)
			(stroke
				(width 0.1)
				(type default)
			)
			(layer "F.Fab")
		)
		(fp_line
			(start -0.679446 -0.305149)
			(end -0.120695 -0.304969)
			(stroke
				(width 0.1)
				(type default)
			)
			(layer "F.Fab")
		)
		(fp_line
			(start -0.120695 0.279466)
			(end -0.120515 0.30479)
			(stroke
				(width 0.1)
				(type default)
			)
			(layer "F.Fab")
		)
		(fp_line
			(start -0.120515 0.30479)
			(end -0.679446 0.30479)
			(stroke
				(width 0.1)
				(type default)
			)
			(layer "F.Fab")
		)
		(fp_line
			(start -0.679446 0.30479)
			(end -0.679446 -0.305149)
			(stroke
				(width 0.1)
				(type default)
			)
			(layer "F.Fab")
		)
		(pad "1" smd circle
			(at -0.40005 0 135)
			(size 0 0)
			(layers "F.Cu" "F.Mask" "F.Paste")
			(net "GND")
		)
		(pad "2" smd circle
			(at 0.40005 0 135)
			(size 0 0)
			(layers "F.Cu" "F.Mask" "F.Paste")
			(net "PEX1_SPARE0")
		)
	)
	(footprint ""
		(layer "F.Cu")
		(at 29.422344 -250.070874 -90)
		(property "Reference" "R1155"
			(at 0 0 270)
			(layer "F.SilkS")
			(hide yes)
			(effects
				(font
					(size 1.27 1.27)
				)
			)
		)
		(property "Value" ""
			(at 0 0 270)
			(layer "F.Fab")
			(effects
				(font
					(size 1.27 1.27)
				)
			)
		)
		(duplicate_pad_numbers_are_jumpers no)
		(fp_line
			(start -0.7874 0.4064)
			(end -0.7874 -0.4064)
			(stroke
				(width 0.1524)
				(type default)
			)
			(layer "F.SilkS")
		)
		(fp_line
			(start 0.7874 0.4064)
			(end -0.7874 0.4064)
			(stroke
				(width 0.1524)
				(type default)
			)
			(layer "F.SilkS")
		)
		(fp_line
			(start -0.7874 -0.4064)
			(end 0.7874 -0.4064)
			(stroke
				(width 0.1524)
				(type default)
			)
			(layer "F.SilkS")
		)
		(fp_line
			(start 0.7874 -0.4064)
			(end 0.7874 0.4064)
			(stroke
				(width 0.1524)
				(type default)
			)
			(layer "F.SilkS")
		)
		(fp_line
			(start -0.67945 0.3048)
			(end -0.67945 -0.305054)
			(stroke
				(width 0.1)
				(type default)
			)
			(layer "F.Fab")
		)
		(fp_line
			(start -0.12065 0.3048)
			(end -0.67945 0.3048)
			(stroke
				(width 0.1)
				(type default)
			)
			(layer "F.Fab")
		)
		(fp_line
			(start 0.120396 0.3048)
			(end 0.120396 0.2794)
			(stroke
				(width 0.1)
				(type default)
			)
			(layer "F.Fab")
		)
		(fp_line
			(start 0.67945 0.3048)
			(end 0.120396 0.3048)
			(stroke
				(width 0.1)
				(type default)
			)
			(layer "F.Fab")
		)
		(fp_line
			(start -0.12065 0.2794)
			(end -0.12065 0.3048)
			(stroke
				(width 0.1)
				(type default)
			)
			(layer "F.Fab")
		)
		(fp_line
			(start 0.120396 0.2794)
			(end -0.12065 0.2794)
			(stroke
				(width 0.1)
				(type default)
			)
			(layer "F.Fab")
		)
		(fp_line
			(start -0.12065 -0.2794)
			(end 0.12065 -0.2794)
			(stroke
				(width 0.1)
				(type default)
			)
			(layer "F.Fab")
		)
		(fp_line
			(start 0.12065 -0.2794)
			(end 0.12065 -0.3048)
			(stroke
				(width 0.1)
				(type default)
			)
			(layer "F.Fab")
		)
		(fp_line
			(start 0.12065 -0.3048)
			(end 0.67945 -0.3048)
			(stroke
				(width 0.1)
				(type default)
			)
			(layer "F.Fab")
		)
		(fp_line
			(start 0.67945 -0.3048)
			(end 0.67945 0.3048)
			(stroke
				(width 0.1)
				(type default)
			)
			(layer "F.Fab")
		)
		(fp_line
			(start -0.67945 -0.305054)
			(end -0.12065 -0.305054)
			(stroke
				(width 0.1)
				(type default)
			)
			(layer "F.Fab")
		)
		(fp_line
			(start -0.12065 -0.305054)
			(end -0.12065 -0.2794)
			(stroke
				(width 0.1)
				(type default)
			)
			(layer "F.Fab")
		)
		(pad "1" smd circle
			(at -0.40005 0 270)
			(size 0 0)
			(layers "F.Cu" "F.Mask" "F.Paste")
			(net "PEX0_MODE_SEL3")
		)
		(pad "2" smd circle
			(at 0.40005 0 270)
			(size 0 0)
			(layers "F.Cu" "F.Mask" "F.Paste")
			(net "P1V8_PEX")
		)
	)
	(footprint ""
		(layer "F.Cu")
		(at 316.500764 -350.098614 90)
		(property "Reference" "C554"
			(at 0 0 90)
			(layer "F.SilkS")
			(hide yes)
			(effects
				(font
					(size 1.27 1.27)
				)
			)
		)
		(property "Value" ""
			(at 0 0 90)
			(layer "F.Fab")
			(effects
				(font
					(size 1.27 1.27)
				)
			)
		)
		(duplicate_pad_numbers_are_jumpers no)
		(fp_line
			(start 0.299974 -0.150114)
			(end 0.299974 0.150114)
			(stroke
				(width 0.1)
				(type default)
			)
			(layer "F.Fab")
		)
		(fp_line
			(start -0.299974 -0.150114)
			(end 0.299974 -0.150114)
			(stroke
				(width 0.1)
				(type default)
			)
			(layer "F.Fab")
		)
		(fp_line
			(start 0.299974 0.150114)
			(end -0.299974 0.150114)
			(stroke
				(width 0.1)
				(type default)
			)
			(layer "F.Fab")
		)
		(fp_line
			(start -0.299974 0.150114)
			(end -0.299974 -0.150114)
			(stroke
				(width 0.1)
				(type default)
			)
			(layer "F.Fab")
		)
		(pad "1" smd rect
			(at -0.2667 0 90)
			(size 0.3048 0.381)
			(layers "F.Cu" "F.Mask" "F.Paste")
			(net "P5E_PEX2_STN6_TX_DN<110>")
		)
		(pad "2" smd rect
			(at 0.2667 0 90)
			(size 0.3048 0.381)
			(layers "F.Cu" "F.Mask" "F.Paste")
			(net "P5E_PEX2_STN6_TX_C_DN<110>")
		)
	)
	(footprint ""
		(layer "F.Cu")
		(at 16.837914 -413.969708 90)
		(property "Reference" "R5595"
			(at 0 0 90)
			(layer "F.SilkS")
			(hide yes)
			(effects
				(font
					(size 1.27 1.27)
				)
			)
		)
		(property "Value" ""
			(at 0 0 90)
			(layer "F.Fab")
			(effects
				(font
					(size 1.27 1.27)
				)
			)
		)
		(duplicate_pad_numbers_are_jumpers no)
		(fp_line
			(start 0.7874 -0.4064)
			(end 0.7874 0.4064)
			(stroke
				(width 0.1524)
				(type default)
			)
			(layer "F.SilkS")
		)
		(fp_line
			(start -0.7874 -0.4064)
			(end 0.7874 -0.4064)
			(stroke
				(width 0.1524)
				(type default)
			)
			(layer "F.SilkS")
		)
		(fp_line
			(start 0.7874 0.4064)
			(end -0.7874 0.4064)
			(stroke
				(width 0.1524)
				(type default)
			)
			(layer "F.SilkS")
		)
		(fp_line
			(start -0.7874 0.4064)
			(end -0.7874 -0.4064)
			(stroke
				(width 0.1524)
				(type default)
			)
			(layer "F.SilkS")
		)
		(fp_line
			(start -0.12065 -0.305054)
			(end -0.12065 -0.2794)
			(stroke
				(width 0.1)
				(type default)
			)
			(layer "F.Fab")
		)
		(fp_line
			(start -0.67945 -0.305054)
			(end -0.12065 -0.305054)
			(stroke
				(width 0.1)
				(type default)
			)
			(layer "F.Fab")
		)
		(fp_line
			(start 0.67945 -0.3048)
			(end 0.67945 0.3048)
			(stroke
				(width 0.1)
				(type default)
			)
			(layer "F.Fab")
		)
		(fp_line
			(start 0.12065 -0.3048)
			(end 0.67945 -0.3048)
			(stroke
				(width 0.1)
				(type default)
			)
			(layer "F.Fab")
		)
		(fp_line
			(start 0.12065 -0.2794)
			(end 0.12065 -0.3048)
			(stroke
				(width 0.1)
				(type default)
			)
			(layer "F.Fab")
		)
		(fp_line
			(start -0.12065 -0.2794)
			(end 0.12065 -0.2794)
			(stroke
				(width 0.1)
				(type default)
			)
			(layer "F.Fab")
		)
		(fp_line
			(start 0.120396 0.2794)
			(end -0.12065 0.2794)
			(stroke
				(width 0.1)
				(type default)
			)
			(layer "F.Fab")
		)
		(fp_line
			(start -0.12065 0.2794)
			(end -0.12065 0.3048)
			(stroke
				(width 0.1)
				(type default)
			)
			(layer "F.Fab")
		)
		(fp_line
			(start 0.67945 0.3048)
			(end 0.120396 0.3048)
			(stroke
				(width 0.1)
				(type default)
			)
			(layer "F.Fab")
		)
		(fp_line
			(start 0.120396 0.3048)
			(end 0.120396 0.2794)
			(stroke
				(width 0.1)
				(type default)
			)
			(layer "F.Fab")
		)
		(fp_line
			(start -0.12065 0.3048)
			(end -0.67945 0.3048)
			(stroke
				(width 0.1)
				(type default)
			)
			(layer "F.Fab")
		)
		(fp_line
			(start -0.67945 0.3048)
			(end -0.67945 -0.305054)
			(stroke
				(width 0.1)
				(type default)
			)
			(layer "F.Fab")
		)
		(pad "1" smd circle
			(at -0.40005 0 90)
			(size 0 0)
			(layers "F.Cu" "F.Mask" "F.Paste")
			(net "LM75_0_A0")
		)
		(pad "2" smd circle
			(at 0.40005 0 90)
			(size 0 0)
			(layers "F.Cu" "F.Mask" "F.Paste")
			(net "GND")
		)
	)
)
